(kicad_pcb
	(version 20260206)
	(generator "pcbnew")
	(generator_version "10.0")
	(general
		(thickness 1.6)
		(legacy_teardrops no)
	)
	(paper "A4")
	(title_block
		(title "panther-plus-userver — 13130-1b_20150205.brd")
		(comment 1 "Honey Badger (Wiwynn) / footprints 138-145 of 1509")
	)
	(layers
		(0 "F.Cu" signal "TOP")
		(4 "In1.Cu" signal "L2")
		(6 "In2.Cu" signal "L3")
		(8 "In3.Cu" signal "L4")
		(10 "In4.Cu" signal "L5")
		(12 "In5.Cu" signal "L6")
		(14 "In6.Cu" signal "L7")
		(16 "In7.Cu" signal "L8")
		(18 "In8.Cu" signal "L9")
		(20 "In9.Cu" signal "L10")
		(22 "In10.Cu" signal "L11")
		(2 "B.Cu" signal "BOTTOM")
		(9 "F.Adhes" user "F.Adhesive")
		(11 "B.Adhes" user "B.Adhesive")
		(13 "F.Paste" user "Package Geometry/Pastemask Top")
		(15 "B.Paste" user "Package Geometry/Pastemask Bottom")
		(5 "F.SilkS" user "Ref Des/Silkscreen Top")
		(7 "B.SilkS" user "Ref Des/Silkscreen Bottom")
		(1 "F.Mask" user "Board Geometry/Soldermask Top")
		(3 "B.Mask" user "Board Geometry/Soldermask Bottom")
		(17 "Dwgs.User" user "User.Drawings")
		(19 "Cmts.User" user "User.Comments")
		(21 "Eco1.User" user "User.Eco1")
		(23 "Eco2.User" user "User.Eco2")
		(25 "Edge.Cuts" user "Board Geometry/Outline")
		(27 "Margin" user)
		(31 "F.CrtYd" user "Package Geometry/Place Bound Top")
		(29 "B.CrtYd" user "Package Geometry/Place Bound Bottom")
		(35 "F.Fab" user "Ref Des/Assembly Top")
		(33 "B.Fab" user "Ref Des/Assembly Bottom")
	)
	(footprint ""
		(layer "F.Cu")
		(at 183.642 -46.101 180)
		(property "Reference" "R217"
			(at 0 0 180)
			(layer "F.SilkS")
			(hide yes)
			(effects
				(font
					(size 1.27 1.27)
				)
			)
		)
		(property "Value" "0R2J-2-GP"
			(at 0.064008 -3.993896 180)
			(unlocked yes)
			(layer "F.Fab")
			(hide yes)
			(effects
				(font
					(size 1.016 1.016)
					(thickness 0.1524)
				)
			)
		)
		(property "Device Type" "R402H16"
			(at 0.064008 -5.517896 180)
			(unlocked yes)
			(layer "F.Fab")
			(hide yes)
			(effects
				(font
					(size 1.016 1.016)
					(thickness 0.1524)
				)
			)
		)
		(duplicate_pad_numbers_are_jumpers no)
		(fp_rect
			(start -0.381 0.8382)
			(end 0.381 -0.8382)
			(stroke
				(width 0)
				(type default)
			)
			(fill no)
			(layer "F.CrtYd")
		)
		(fp_rect
			(start -0.381 0.8382)
			(end 0.381 -0.8382)
			(stroke
				(width 0)
				(type default)
			)
			(fill no)
			(layer "F.Fab")
		)
		(pad "1" smd custom
			(at 0 -0.4318 180)
			(size 0.127 0.127)
			(layers "F.Cu" "F.Mask" "F.Paste")
			(net "SMB_HOST_LV_CLK")
			(options
				(clearance outline)
				(anchor circle)
			)
			(primitives
				(gr_poly
					(pts
						(arc
							(start -0.2032 -0.2794)
							(mid -0.239121 -0.264521)
							(end -0.254 -0.2286)
						)
						(arc
							(start -0.254 0.2286)
							(mid -0.239121 0.264521)
							(end -0.2032 0.2794)
						)
						(arc
							(start 0.2032 0.2794)
							(mid 0.239121 0.264521)
							(end 0.254 0.2286)
						)
						(arc
							(start 0.254 -0.2286)
							(mid 0.239121 -0.264521)
							(end 0.2032 -0.2794)
						)
					)
					(width 0)
					(fill yes)
				)
			)
		)
		(pad "2" smd custom
			(at 0 0.4318 180)
			(size 0.127 0.127)
			(layers "F.Cu" "F.Mask" "F.Paste")
			(net "SMB_DPOT_CLK")
			(options
				(clearance outline)
				(anchor circle)
			)
			(primitives
				(gr_poly
					(pts
						(arc
							(start -0.2032 -0.2794)
							(mid -0.239121 -0.264521)
							(end -0.254 -0.2286)
						)
						(arc
							(start -0.254 0.2286)
							(mid -0.239121 0.264521)
							(end -0.2032 0.2794)
						)
						(arc
							(start 0.2032 0.2794)
							(mid 0.239121 0.264521)
							(end 0.254 0.2286)
						)
						(arc
							(start 0.254 -0.2286)
							(mid 0.239121 -0.264521)
							(end 0.2032 -0.2794)
						)
					)
					(width 0)
					(fill yes)
				)
			)
		)
	)
	(footprint ""
		(layer "F.Cu")
		(at 167.64 -30.2514 -90)
		(property "Reference" "PR132"
			(at 0 0 270)
			(layer "F.SilkS")
			(hide yes)
			(effects
				(font
					(size 1.27 1.27)
				)
			)
		)
		(property "Value" "0R3J-6-GP"
			(at -0.0254 -2.5146 270)
			(unlocked yes)
			(layer "F.Fab")
			(hide yes)
			(effects
				(font
					(size 1.016 1.016)
					(thickness 0.1524)
				)
			)
		)
		(property "Device Type" "R603H22"
			(at -0.0254 -4.0386 270)
			(unlocked yes)
			(layer "F.Fab")
			(hide yes)
			(effects
				(font
					(size 1.016 1.016)
					(thickness 0.1524)
				)
			)
		)
		(duplicate_pad_numbers_are_jumpers no)
		(fp_line
			(start -0.2032 0)
			(end -0.4191 0)
			(stroke
				(width 0.2032)
				(type default)
			)
			(layer "F.SilkS")
		)
		(fp_line
			(start 0.4318 0)
			(end 0.2032 0)
			(stroke
				(width 0.2032)
				(type default)
			)
			(layer "F.SilkS")
		)
		(fp_rect
			(start -0.635 1.1811)
			(end 0.635 -1.1811)
			(stroke
				(width 0)
				(type default)
			)
			(fill no)
			(layer "F.CrtYd")
		)
		(fp_rect
			(start -0.635 1.1811)
			(end 0.635 -1.1811)
			(stroke
				(width 0)
				(type default)
			)
			(fill no)
			(layer "F.Fab")
		)
		(pad "1" smd custom
			(at 0 -0.6604 270)
			(size 0.19685 0.19685)
			(layers "F.Cu" "F.Mask" "F.Paste")
			(net "P1V8_STBY_LDO_IN1")
			(options
				(clearance outline)
				(anchor circle)
			)
			(primitives
				(gr_poly
					(pts
						(arc
							(start 0.508 -0.2921)
							(mid 0.478242 -0.363942)
							(end 0.4064 -0.3937)
						)
						(arc
							(start -0.4064 -0.3937)
							(mid -0.478242 -0.363942)
							(end -0.508 -0.2921)
						)
						(arc
							(start -0.508 0.2921)
							(mid -0.478242 0.363942)
							(end -0.4064 0.3937)
						)
						(arc
							(start 0.4064 0.3937)
							(mid 0.478242 0.363942)
							(end 0.508 0.2921)
						)
					)
					(width 0)
					(fill yes)
				)
			)
		)
		(pad "2" smd custom
			(at 0 0.6604 270)
			(size 0.19685 0.19685)
			(layers "F.Cu" "F.Mask" "F.Paste")
			(net "P3V3_STBY")
			(options
				(clearance outline)
				(anchor circle)
			)
			(primitives
				(gr_poly
					(pts
						(arc
							(start 0.508 -0.2921)
							(mid 0.478242 -0.363942)
							(end 0.4064 -0.3937)
						)
						(arc
							(start -0.4064 -0.3937)
							(mid -0.478242 -0.363942)
							(end -0.508 -0.2921)
						)
						(arc
							(start -0.508 0.2921)
							(mid -0.478242 0.363942)
							(end -0.4064 0.3937)
						)
						(arc
							(start 0.4064 0.3937)
							(mid 0.478242 0.363942)
							(end 0.508 0.2921)
						)
					)
					(width 0)
					(fill yes)
				)
			)
		)
	)
	(footprint ""
		(layer "F.Cu")
		(at 130.302 -45.466 -90)
		(property "Reference" "C11"
			(at 0 0 270)
			(layer "F.SilkS")
			(hide yes)
			(effects
				(font
					(size 1.27 1.27)
				)
			)
		)
		(property "Value" "SCD1U10V2KX-5GP"
			(at 1.1811 -2.7051 270)
			(unlocked yes)
			(layer "F.Fab")
			(hide yes)
			(effects
				(font
					(size 1.016 1.016)
					(thickness 0.1524)
				)
			)
		)
		(property "Device Type" "C402H22"
			(at 1.1811 -4.2291 270)
			(unlocked yes)
			(layer "F.Fab")
			(hide yes)
			(effects
				(font
					(size 1.016 1.016)
					(thickness 0.1524)
				)
			)
		)
		(duplicate_pad_numbers_are_jumpers no)
		(fp_rect
			(start -0.381 0.7366)
			(end 0.381 -0.7366)
			(stroke
				(width 0)
				(type default)
			)
			(fill no)
			(layer "F.CrtYd")
		)
		(fp_rect
			(start -0.381 0.7366)
			(end 0.381 -0.7366)
			(stroke
				(width 0)
				(type default)
			)
			(fill no)
			(layer "F.Fab")
		)
		(pad "1" smd custom
			(at 0 -0.4572 270)
			(size 0.1143 0.1143)
			(layers "F.Cu" "F.Mask" "F.Paste")
			(net "P1V2_FPGA_A")
			(options
				(clearance outline)
				(anchor circle)
			)
			(primitives
				(gr_poly
					(pts
						(arc
							(start -0.254 -0.1778)
							(mid -0.239121 -0.213721)
							(end -0.2032 -0.2286)
						)
						(arc
							(start 0.2032 -0.2286)
							(mid 0.239121 -0.213721)
							(end 0.254 -0.1778)
						)
						(arc
							(start 0.254 0.1778)
							(mid 0.239121 0.213721)
							(end 0.2032 0.2286)
						)
						(arc
							(start -0.2032 0.2286)
							(mid -0.239121 0.213721)
							(end -0.254 0.1778)
						)
					)
					(width 0)
					(fill yes)
				)
			)
		)
		(pad "2" smd custom
			(at 0 0.4572 270)
			(size 0.1143 0.1143)
			(layers "F.Cu" "F.Mask" "F.Paste")
			(net "GND")
			(options
				(clearance outline)
				(anchor circle)
			)
			(primitives
				(gr_poly
					(pts
						(arc
							(start -0.254 -0.1778)
							(mid -0.239121 -0.213721)
							(end -0.2032 -0.2286)
						)
						(arc
							(start 0.2032 -0.2286)
							(mid 0.239121 -0.213721)
							(end 0.254 -0.1778)
						)
						(arc
							(start 0.254 0.1778)
							(mid 0.239121 0.213721)
							(end 0.2032 0.2286)
						)
						(arc
							(start -0.2032 0.2286)
							(mid -0.239121 0.213721)
							(end -0.254 0.1778)
						)
					)
					(width 0)
					(fill yes)
				)
			)
		)
	)
	(footprint ""
		(layer "F.Cu")
		(at 153.7462 -59.182)
		(property "Reference" "C97"
			(at 0 0 0)
			(layer "F.SilkS")
			(hide yes)
			(effects
				(font
					(size 1.27 1.27)
				)
			)
		)
		(property "Value" "SC10U6D3V3MX-GP"
			(at 0 -2.8194 0)
			(unlocked yes)
			(layer "F.Fab")
			(hide yes)
			(effects
				(font
					(size 1.016 1.016)
					(thickness 0.1524)
				)
			)
		)
		(property "Device Type" "C603H38"
			(at 0 -4.3434 0)
			(unlocked yes)
			(layer "F.Fab")
			(hide yes)
			(effects
				(font
					(size 1.016 1.016)
					(thickness 0.1524)
				)
			)
		)
		(duplicate_pad_numbers_are_jumpers no)
		(fp_line
			(start -0.4064 0)
			(end 0.4064 0)
			(stroke
				(width 0.2286)
				(type default)
			)
			(layer "F.SilkS")
		)
		(fp_rect
			(start -0.635 1.1811)
			(end 0.635 -1.1811)
			(stroke
				(width 0)
				(type default)
			)
			(fill no)
			(layer "F.CrtYd")
		)
		(fp_rect
			(start -0.635 1.1811)
			(end 0.635 -1.1811)
			(stroke
				(width 0)
				(type default)
			)
			(fill no)
			(layer "F.Fab")
		)
		(pad "1" smd custom
			(at 0 -0.6604)
			(size 0.19685 0.19685)
			(layers "F.Cu" "F.Mask" "F.Paste")
			(net "PV_VDDR")
			(options
				(clearance outline)
				(anchor circle)
			)
			(primitives
				(gr_poly
					(pts
						(arc
							(start 0.508 -0.2921)
							(mid 0.478242 -0.363942)
							(end 0.4064 -0.3937)
						)
						(arc
							(start -0.4064 -0.3937)
							(mid -0.478242 -0.363942)
							(end -0.508 -0.2921)
						)
						(arc
							(start -0.508 0.2921)
							(mid -0.478242 0.363942)
							(end -0.4064 0.3937)
						)
						(arc
							(start 0.4064 0.3937)
							(mid 0.478242 0.363942)
							(end 0.508 0.2921)
						)
					)
					(width 0)
					(fill yes)
				)
			)
		)
		(pad "2" smd custom
			(at 0 0.6604)
			(size 0.19685 0.19685)
			(layers "F.Cu" "F.Mask" "F.Paste")
			(net "GND")
			(options
				(clearance outline)
				(anchor circle)
			)
			(primitives
				(gr_poly
					(pts
						(arc
							(start 0.508 -0.2921)
							(mid 0.478242 -0.363942)
							(end 0.4064 -0.3937)
						)
						(arc
							(start -0.4064 -0.3937)
							(mid -0.478242 -0.363942)
							(end -0.508 -0.2921)
						)
						(arc
							(start -0.508 0.2921)
							(mid -0.478242 0.363942)
							(end -0.4064 0.3937)
						)
						(arc
							(start 0.4064 0.3937)
							(mid 0.478242 0.363942)
							(end 0.508 0.2921)
						)
					)
					(width 0)
					(fill yes)
				)
			)
		)
	)
	(footprint ""
		(layer "F.Cu")
		(at 74.422 -49.276 180)
		(property "Reference" "R45"
			(at 0 0 180)
			(layer "F.SilkS")
			(hide yes)
			(effects
				(font
					(size 1.27 1.27)
				)
			)
		)
		(property "Value" "1KR2F-3-GP"
			(at 0.064008 -3.993896 180)
			(unlocked yes)
			(layer "F.Fab")
			(hide yes)
			(effects
				(font
					(size 1.016 1.016)
					(thickness 0.1524)
				)
			)
		)
		(property "Device Type" "R402H16"
			(at 0.064008 -5.517896 180)
			(unlocked yes)
			(layer "F.Fab")
			(hide yes)
			(effects
				(font
					(size 1.016 1.016)
					(thickness 0.1524)
				)
			)
		)
		(duplicate_pad_numbers_are_jumpers no)
		(fp_rect
			(start -0.381 0.8382)
			(end 0.381 -0.8382)
			(stroke
				(width 0)
				(type default)
			)
			(fill no)
			(layer "F.CrtYd")
		)
		(fp_rect
			(start -0.381 0.8382)
			(end 0.381 -0.8382)
			(stroke
				(width 0)
				(type default)
			)
			(fill no)
			(layer "F.Fab")
		)
		(pad "1" smd custom
			(at 0 -0.4318 180)
			(size 0.127 0.127)
			(layers "F.Cu" "F.Mask" "F.Paste")
			(net "BD_ID_0")
			(options
				(clearance outline)
				(anchor circle)
			)
			(primitives
				(gr_poly
					(pts
						(arc
							(start -0.2032 -0.2794)
							(mid -0.239121 -0.264521)
							(end -0.254 -0.2286)
						)
						(arc
							(start -0.254 0.2286)
							(mid -0.239121 0.264521)
							(end -0.2032 0.2794)
						)
						(arc
							(start 0.2032 0.2794)
							(mid 0.239121 0.264521)
							(end 0.254 0.2286)
						)
						(arc
							(start 0.254 -0.2286)
							(mid 0.239121 -0.264521)
							(end 0.2032 -0.2794)
						)
					)
					(width 0)
					(fill yes)
				)
			)
		)
		(pad "2" smd custom
			(at 0 0.4318 180)
			(size 0.127 0.127)
			(layers "F.Cu" "F.Mask" "F.Paste")
			(net "GND")
			(options
				(clearance outline)
				(anchor circle)
			)
			(primitives
				(gr_poly
					(pts
						(arc
							(start -0.2032 -0.2794)
							(mid -0.239121 -0.264521)
							(end -0.254 -0.2286)
						)
						(arc
							(start -0.254 0.2286)
							(mid -0.239121 0.264521)
							(end -0.2032 0.2794)
						)
						(arc
							(start 0.2032 0.2794)
							(mid 0.239121 0.264521)
							(end 0.254 0.2286)
						)
						(arc
							(start 0.254 -0.2286)
							(mid 0.239121 -0.264521)
							(end 0.2032 -0.2794)
						)
					)
					(width 0)
					(fill yes)
				)
			)
		)
	)
	(footprint ""
		(layer "F.Cu")
		(at 5.5626 -50.546)
		(property "Reference" "R5"
			(at 0 0 0)
			(layer "F.SilkS")
			(hide yes)
			(effects
				(font
					(size 1.27 1.27)
				)
			)
		)
		(property "Value" "4K7R2F-GP"
			(at 0.064008 -3.993896 0)
			(unlocked yes)
			(layer "F.Fab")
			(hide yes)
			(effects
				(font
					(size 1.016 1.016)
					(thickness 0.1524)
				)
			)
		)
		(property "Device Type" "R402H16"
			(at 0.064008 -5.517896 0)
			(unlocked yes)
			(layer "F.Fab")
			(hide yes)
			(effects
				(font
					(size 1.016 1.016)
					(thickness 0.1524)
				)
			)
		)
		(duplicate_pad_numbers_are_jumpers no)
		(fp_rect
			(start -0.381 0.8382)
			(end 0.381 -0.8382)
			(stroke
				(width 0)
				(type default)
			)
			(fill no)
			(layer "F.CrtYd")
		)
		(fp_rect
			(start -0.381 0.8382)
			(end 0.381 -0.8382)
			(stroke
				(width 0)
				(type default)
			)
			(fill no)
			(layer "F.Fab")
		)
		(pad "1" smd custom
			(at 0 -0.4318)
			(size 0.127 0.127)
			(layers "F.Cu" "F.Mask" "F.Paste")
			(net "P3V3_STBY")
			(options
				(clearance outline)
				(anchor circle)
			)
			(primitives
				(gr_poly
					(pts
						(arc
							(start -0.2032 -0.2794)
							(mid -0.239121 -0.264521)
							(end -0.254 -0.2286)
						)
						(arc
							(start -0.254 0.2286)
							(mid -0.239121 0.264521)
							(end -0.2032 0.2794)
						)
						(arc
							(start 0.2032 0.2794)
							(mid 0.239121 0.264521)
							(end 0.254 0.2286)
						)
						(arc
							(start 0.254 -0.2286)
							(mid 0.239121 -0.264521)
							(end 0.2032 -0.2794)
						)
					)
					(width 0)
					(fill yes)
				)
			)
		)
		(pad "2" smd custom
			(at 0 0.4318)
			(size 0.127 0.127)
			(layers "F.Cu" "F.Mask" "F.Paste")
			(net "TEMP_1_A0")
			(options
				(clearance outline)
				(anchor circle)
			)
			(primitives
				(gr_poly
					(pts
						(arc
							(start -0.2032 -0.2794)
							(mid -0.239121 -0.264521)
							(end -0.254 -0.2286)
						)
						(arc
							(start -0.254 0.2286)
							(mid -0.239121 0.264521)
							(end -0.2032 0.2794)
						)
						(arc
							(start 0.2032 0.2794)
							(mid 0.239121 0.264521)
							(end 0.254 0.2286)
						)
						(arc
							(start 0.254 -0.2286)
							(mid 0.239121 -0.264521)
							(end 0.2032 -0.2794)
						)
					)
					(width 0)
					(fill yes)
				)
			)
		)
	)
	(footprint ""
		(layer "F.Cu")
		(at 140.589 -51.3588 -90)
		(property "Reference" "R87"
			(at 0 0 270)
			(layer "F.SilkS")
			(hide yes)
			(effects
				(font
					(size 1.27 1.27)
				)
			)
		)
		(property "Value" "4K7R2F-GP"
			(at 1.7907 -1.1176 270)
			(unlocked yes)
			(layer "F.Fab")
			(hide yes)
			(effects
				(font
					(size 1.016 1.016)
					(thickness 0.1524)
				)
			)
		)
		(property "Device Type" "R402H16"
			(at 1.7907 -2.6416 270)
			(unlocked yes)
			(layer "F.Fab")
			(hide yes)
			(effects
				(font
					(size 1.016 1.016)
					(thickness 0.1524)
				)
			)
		)
		(duplicate_pad_numbers_are_jumpers no)
		(fp_rect
			(start -0.381 0.8382)
			(end 0.381 -0.8382)
			(stroke
				(width 0)
				(type default)
			)
			(fill no)
			(layer "F.CrtYd")
		)
		(fp_rect
			(start -0.381 0.8382)
			(end 0.381 -0.8382)
			(stroke
				(width 0)
				(type default)
			)
			(fill no)
			(layer "F.Fab")
		)
		(pad "1" smd custom
			(at 0 -0.4318 270)
			(size 0.127 0.127)
			(layers "F.Cu" "F.Mask" "F.Paste")
			(net "SPI_SW_ADDR1")
			(options
				(clearance outline)
				(anchor circle)
			)
			(primitives
				(gr_poly
					(pts
						(arc
							(start -0.2032 -0.2794)
							(mid -0.239121 -0.264521)
							(end -0.254 -0.2286)
						)
						(arc
							(start -0.254 0.2286)
							(mid -0.239121 0.264521)
							(end -0.2032 0.2794)
						)
						(arc
							(start 0.2032 0.2794)
							(mid 0.239121 0.264521)
							(end 0.254 0.2286)
						)
						(arc
							(start 0.254 -0.2286)
							(mid 0.239121 -0.264521)
							(end 0.2032 -0.2794)
						)
					)
					(width 0)
					(fill yes)
				)
			)
		)
		(pad "2" smd custom
			(at 0 0.4318 270)
			(size 0.127 0.127)
			(layers "F.Cu" "F.Mask" "F.Paste")
			(net "GND")
			(options
				(clearance outline)
				(anchor circle)
			)
			(primitives
				(gr_poly
					(pts
						(arc
							(start -0.2032 -0.2794)
							(mid -0.239121 -0.264521)
							(end -0.254 -0.2286)
						)
						(arc
							(start -0.254 0.2286)
							(mid -0.239121 0.264521)
							(end -0.2032 0.2794)
						)
						(arc
							(start 0.2032 0.2794)
							(mid 0.239121 0.264521)
							(end 0.254 0.2286)
						)
						(arc
							(start 0.254 -0.2286)
							(mid 0.239121 -0.264521)
							(end 0.2032 -0.2794)
						)
					)
					(width 0)
					(fill yes)
				)
			)
		)
	)
	(footprint ""
		(layer "F.Cu")
		(at 66.802 -57.658)
		(property "Reference" "R473"
			(at 0 0 0)
			(layer "F.SilkS")
			(hide yes)
			(effects
				(font
					(size 1.27 1.27)
				)
			)
		)
		(property "Value" "0R2J-2-GP"
			(at 1.7907 -1.1176 0)
			(unlocked yes)
			(layer "F.Fab")
			(hide yes)
			(effects
				(font
					(size 1.016 1.016)
					(thickness 0.1524)
				)
			)
		)
		(property "Device Type" "R402H16"
			(at 1.7907 -2.6416 0)
			(unlocked yes)
			(layer "F.Fab")
			(hide yes)
			(effects
				(font
					(size 1.016 1.016)
					(thickness 0.1524)
				)
			)
		)
		(duplicate_pad_numbers_are_jumpers no)
		(fp_rect
			(start -0.381 0.8382)
			(end 0.381 -0.8382)
			(stroke
				(width 0)
				(type default)
			)
			(fill no)
			(layer "F.CrtYd")
		)
		(fp_rect
			(start -0.381 0.8382)
			(end 0.381 -0.8382)
			(stroke
				(width 0)
				(type default)
			)
			(fill no)
			(layer "F.Fab")
		)
		(pad "1" smd custom
			(at 0 -0.4318)
			(size 0.127 0.127)
			(layers "F.Cu" "F.Mask" "F.Paste")
			(net "FPGA_SMB_HOST_CLK")
			(options
				(clearance outline)
				(anchor circle)
			)
			(primitives
				(gr_poly
					(pts
						(arc
							(start -0.2032 -0.2794)
							(mid -0.239121 -0.264521)
							(end -0.254 -0.2286)
						)
						(arc
							(start -0.254 0.2286)
							(mid -0.239121 0.264521)
							(end -0.2032 0.2794)
						)
						(arc
							(start 0.2032 0.2794)
							(mid 0.239121 0.264521)
							(end 0.254 0.2286)
						)
						(arc
							(start 0.254 -0.2286)
							(mid 0.239121 -0.264521)
							(end 0.2032 -0.2794)
						)
					)
					(width 0)
					(fill yes)
				)
			)
		)
		(pad "2" smd custom
			(at 0 0.4318)
			(size 0.127 0.127)
			(layers "F.Cu" "F.Mask" "F.Paste")
			(net "FPGA_SMB_HOST_R_CLK")
			(options
				(clearance outline)
				(anchor circle)
			)
			(primitives
				(gr_poly
					(pts
						(arc
							(start -0.2032 -0.2794)
							(mid -0.239121 -0.264521)
							(end -0.254 -0.2286)
						)
						(arc
							(start -0.254 0.2286)
							(mid -0.239121 0.264521)
							(end -0.2032 0.2794)
						)
						(arc
							(start 0.2032 0.2794)
							(mid 0.239121 0.264521)
							(end 0.254 0.2286)
						)
						(arc
							(start 0.254 -0.2286)
							(mid 0.239121 -0.264521)
							(end 0.2032 -0.2794)
						)
					)
					(width 0)
					(fill yes)
				)
			)
		)
	)
)
